#ISCELL
  mstr_misc dns *
  *
#ISCELL
  mstr_symbols design_note *
  *
#ISCELL
  mstr_symbols intel_corp_bpage *
  *
#CELL
  mstr_discrete res *
  page214_i101
#ISCELL
  mstr_symbols gnd *
  page214_i102
#ISCELL
  mstr_standard offpage *
  page214_i103
#CELL
  mstr_discrete res *
  page214_i105
#ISCELL
  mstr_standard offpage *
  page214_i106
#ISCELL
  mstr_symbols pvccio_cpu1 *
  page214_i107
#CELL
  dev_discrete cap_a *
  page214_i108
#CELL
  mstr_discrete res *
  page214_i109
#CELL
  mstr_discrete ir354xx *
  page214_i126
#CELL
  mstr_discrete res *
  page214_i127
#ISCELL
  mstr_symbols gnd *
  page214_i128
#CELL
  mstr_misc shunt *
  page214_i129
#CELL
  mstr_misc shunt *
  page214_i130
#CELL
  w_hdl sc2k2p50v3kx-gp *
  page214_i131
#CELL
  w_hdl 3d01r5f-gp *
  page214_i132
#ISCELL
  mstr_symbols gnd *
  page214_i133
#CELL
  mstr_discrete cap *
  page214_i134
#ISCELL
  mstr_symbols gnd *
  page214_i135
#ISCELL
  mstr_symbols gnd *
  page214_i136
#CELL
  dev_discrete cap_a *
  page214_i137
#CELL
  mstr_discrete res *
  page214_i139
#CELL
  mstr_discrete capp *
  page214_i20
#CELL
  mstr_discrete capp *
  page214_i21
#CELL
  mstr_discrete capp *
  page214_i24
#ISCELL
  mstr_symbols gnd *
  page214_i28
#CELL
  mstr_discrete cap *
  page214_i29
#ISCELL
  mstr_symbols pvccio_cpu1 *
  page214_i3
#ISCELL
  mstr_symbols universal_power *
  page214_i30
#CELL
  mstr_discrete cap *
  page214_i31
#ISCELL
  mstr_symbols gnd *
  page214_i32
#ISCELL
  mstr_standard offpage *
  page214_i58
#ISCELL
  mstr_standard offpage *
  page214_i59
#ISCELL
  mstr_symbols gnd *
  page214_i6
#ISCELL
  mstr_standard offpage *
  page214_i60
#ISCELL
  mstr_symbols pvccio_cpu1 *
  page214_i64
#CELL
  dev_discrete cap_a *
  page214_i65
#ISCELL
  mstr_symbols gnd *
  page214_i66
#CELL
  mstr_discrete inductor *
  page214_i67
#ISCELL
  mstr_symbols gnd *
  page214_i68
#CELL
  mstr_discrete res *
  page214_i71
#CELL
  mstr_discrete cap *
  page214_i73
#CELL
  dev_discrete cap_a *
  page214_i74
#CELL
  mstr_discrete cap *
  page214_i76
#CELL
  dev_discrete cap_a *
  page214_i77
#CELL
  mstr_discrete cap *
  page214_i78
#CELL
  mstr_discrete cap *
  page214_i79
#CELL
  mstr_discrete cap *
  page214_i8
#CELL
  mstr_discrete cap *
  page214_i80
#CELL
  mstr_discrete cap *
  page214_i81
#ISCELL
  mstr_standard offpage *
  page214_i82
#CELL
  mstr_discrete cap *
  page214_i83
#ISCELL
  mstr_symbols gnd *
  page214_i84
#ISCELL
  mstr_symbols p5v_stby *
  page214_i88
#ISCELL
  mstr_symbols universal_power *
  page214_i89
#ISCELL
  mstr_symbols gnd *
  page214_i9
#ISCELL
  mstr_standard offpage *
  page214_i95
#CELL
  dev_discrete cap_a *
  page214_i96
#ISCELL
  mstr_standard offpage *
  page214_i97
